# T6G (Grand Teton) — schematic netlist excerpt (pin names and nets, part order shuffled) for the footprints in the layout excerpt that follows; sources: Cadence DE-HDL packaged netlist, KiCad conversion of 04192023_DAF0TMB3IC0_F0TG_MB_C_brd_V02_OCP.brd

R673  Q_RES  33.2 1% CHIP  pkg 0201LF  page 322 : A = SMB_RT_CPU1_P0_ROM_R_SDA ; B = SMB_RT_CPU1_P0_ROM_SDA
R219  Q_RES  33 5% CHIP  pkg 0402LF  page 81 : A = CPU0_NMI_SYNC_FLOOD_N ; B = FM_CPU0_NMI_SYNC_FLOOD_N
R604  Q_RES  33.2 1% CHIP  pkg 0402LF  page 77 : A = SPI_CPU0_LVC3_D0 ; B = SPI_CPU0_LVC3_SCM_D0

(kicad_pcb
	(version 20260206)
	(generator "pcbnew")
	(generator_version "10.0")
	(general
		(thickness 1.6)
		(legacy_teardrops no)
	)
	(paper "A4")
	(title_block
		(title "04192023_DAF0TMB3IC0_F0TG_MB_C_brd_V02_OCP.brd")
		(comment 1 "Grand Teton / footprints 3544-3546 of 8354")
	)
	(layers
		(0 "F.Cu" signal "TOP")
		(4 "In1.Cu" signal "GND")
		(6 "In2.Cu" signal "IN1")
		(8 "In3.Cu" signal "GND1")
		(10 "In4.Cu" signal "IN2")
		(12 "In5.Cu" signal "GND2")
		(14 "In6.Cu" signal "IN3")
		(16 "In7.Cu" signal "GND3")
		(18 "In8.Cu" signal "VCC")
		(20 "In9.Cu" signal "VCC1")
		(22 "In10.Cu" signal "GND4")
		(24 "In11.Cu" signal "IN4")
		(26 "In12.Cu" signal "GND5")
		(28 "In13.Cu" signal "IN5")
		(30 "In14.Cu" signal "GND6")
		(32 "In15.Cu" signal "IN6")
		(34 "In16.Cu" signal "GND7")
		(2 "B.Cu" signal "BOTTOM")
		(9 "F.Adhes" user "F.Adhesive")
		(11 "B.Adhes" user "B.Adhesive")
		(13 "F.Paste" user "Package Geometry/Pastemask Top")
		(15 "B.Paste" user "Package Geometry/Pastemask Bottom")
		(5 "F.SilkS" user "Ref Des/Silkscreen Top")
		(7 "B.SilkS" user "Ref Des/Silkscreen Bottom")
		(1 "F.Mask" user "Board Geometry/Soldermask Top")
		(3 "B.Mask" user "Board Geometry/Soldermask Bottom")
		(17 "Dwgs.User" user "User.Drawings")
		(19 "Cmts.User" user "User.Comments")
		(21 "Eco1.User" user "User.Eco1")
		(23 "Eco2.User" user "User.Eco2")
		(25 "Edge.Cuts" user "Board Geometry/Outline")
		(27 "Margin" user)
		(31 "F.CrtYd" user "Package Geometry/Place Bound Top")
		(29 "B.CrtYd" user "Package Geometry/Place Bound Bottom")
		(35 "F.Fab" user "Ref Des/Assembly Top")
		(33 "B.Fab" user "Ref Des/Assembly Bottom")
	)
	(footprint ""
		(layer "F.Cu")
		(at 259.070094 -141.968728 90)
		(property "Reference" "R604"
			(at 0 0 90)
			(layer "F.SilkS")
			(hide yes)
			(effects
				(font
					(size 1.27 1.27)
				)
			)
		)
		(property "Value" ""
			(at 0 0 90)
			(layer "F.Fab")
			(effects
				(font
					(size 1.27 1.27)
				)
			)
		)
		(duplicate_pad_numbers_are_jumpers no)
		(fp_line
			(start 0.7874 -0.4064)
			(end 0.7874 0.4064)
			(stroke
				(width 0.1524)
				(type default)
			)
			(layer "F.SilkS")
		)
		(fp_line
			(start -0.7874 -0.4064)
			(end 0.7874 -0.4064)
			(stroke
				(width 0.1524)
				(type default)
			)
			(layer "F.SilkS")
		)
		(fp_line
			(start 0.7874 0.4064)
			(end -0.7874 0.4064)
			(stroke
				(width 0.1524)
				(type default)
			)
			(layer "F.SilkS")
		)
		(fp_line
			(start -0.7874 0.4064)
			(end -0.7874 -0.4064)
			(stroke
				(width 0.1524)
				(type default)
			)
			(layer "F.SilkS")
		)
		(fp_line
			(start -0.12065 -0.305054)
			(end -0.12065 -0.2794)
			(stroke
				(width 0.1)
				(type default)
			)
			(layer "F.Fab")
		)
		(fp_line
			(start -0.67945 -0.305054)
			(end -0.12065 -0.305054)
			(stroke
				(width 0.1)
				(type default)
			)
			(layer "F.Fab")
		)
		(fp_line
			(start 0.67945 -0.3048)
			(end 0.67945 0.3048)
			(stroke
				(width 0.1)
				(type default)
			)
			(layer "F.Fab")
		)
		(fp_line
			(start 0.12065 -0.3048)
			(end 0.67945 -0.3048)
			(stroke
				(width 0.1)
				(type default)
			)
			(layer "F.Fab")
		)
		(fp_line
			(start 0.12065 -0.2794)
			(end 0.12065 -0.3048)
			(stroke
				(width 0.1)
				(type default)
			)
			(layer "F.Fab")
		)
		(fp_line
			(start -0.12065 -0.2794)
			(end 0.12065 -0.2794)
			(stroke
				(width 0.1)
				(type default)
			)
			(layer "F.Fab")
		)
		(fp_line
			(start 0.120396 0.2794)
			(end -0.12065 0.2794)
			(stroke
				(width 0.1)
				(type default)
			)
			(layer "F.Fab")
		)
		(fp_line
			(start -0.12065 0.2794)
			(end -0.12065 0.3048)
			(stroke
				(width 0.1)
				(type default)
			)
			(layer "F.Fab")
		)
		(fp_line
			(start 0.67945 0.3048)
			(end 0.120396 0.3048)
			(stroke
				(width 0.1)
				(type default)
			)
			(layer "F.Fab")
		)
		(fp_line
			(start 0.120396 0.3048)
			(end 0.120396 0.2794)
			(stroke
				(width 0.1)
				(type default)
			)
			(layer "F.Fab")
		)
		(fp_line
			(start -0.12065 0.3048)
			(end -0.67945 0.3048)
			(stroke
				(width 0.1)
				(type default)
			)
			(layer "F.Fab")
		)
		(fp_line
			(start -0.67945 0.3048)
			(end -0.67945 -0.305054)
			(stroke
				(width 0.1)
				(type default)
			)
			(layer "F.Fab")
		)
		(pad "1" smd circle
			(at -0.40005 0 90)
			(size 0 0)
			(layers "F.Cu" "F.Mask" "F.Paste")
			(net "SPI_CPU0_LVC3_D0")
		)
		(pad "2" smd circle
			(at 0.40005 0 90)
			(size 0 0)
			(layers "F.Cu" "F.Mask" "F.Paste")
			(net "SPI_CPU0_LVC3_SCM_D0")
		)
	)
	(footprint ""
		(layer "F.Cu")
		(at 185.49874 -133.548882 -90)
		(property "Reference" "R219"
			(at 0 0 270)
			(layer "F.SilkS")
			(hide yes)
			(effects
				(font
					(size 1.27 1.27)
				)
			)
		)
		(property "Value" ""
			(at 0 0 270)
			(layer "F.Fab")
			(effects
				(font
					(size 1.27 1.27)
				)
			)
		)
		(duplicate_pad_numbers_are_jumpers no)
		(fp_line
			(start -0.7874 0.4064)
			(end -0.7874 -0.4064)
			(stroke
				(width 0.1524)
				(type default)
			)
			(layer "F.SilkS")
		)
		(fp_line
			(start 0.7874 0.4064)
			(end -0.7874 0.4064)
			(stroke
				(width 0.1524)
				(type default)
			)
			(layer "F.SilkS")
		)
		(fp_line
			(start -0.7874 -0.4064)
			(end 0.7874 -0.4064)
			(stroke
				(width 0.1524)
				(type default)
			)
			(layer "F.SilkS")
		)
		(fp_line
			(start 0.7874 -0.4064)
			(end 0.7874 0.4064)
			(stroke
				(width 0.1524)
				(type default)
			)
			(layer "F.SilkS")
		)
		(fp_line
			(start -0.67945 0.3048)
			(end -0.67945 -0.305054)
			(stroke
				(width 0.1)
				(type default)
			)
			(layer "F.Fab")
		)
		(fp_line
			(start -0.12065 0.3048)
			(end -0.67945 0.3048)
			(stroke
				(width 0.1)
				(type default)
			)
			(layer "F.Fab")
		)
		(fp_line
			(start 0.120396 0.3048)
			(end 0.120396 0.2794)
			(stroke
				(width 0.1)
				(type default)
			)
			(layer "F.Fab")
		)
		(fp_line
			(start 0.67945 0.3048)
			(end 0.120396 0.3048)
			(stroke
				(width 0.1)
				(type default)
			)
			(layer "F.Fab")
		)
		(fp_line
			(start -0.12065 0.2794)
			(end -0.12065 0.3048)
			(stroke
				(width 0.1)
				(type default)
			)
			(layer "F.Fab")
		)
		(fp_line
			(start 0.120396 0.2794)
			(end -0.12065 0.2794)
			(stroke
				(width 0.1)
				(type default)
			)
			(layer "F.Fab")
		)
		(fp_line
			(start -0.12065 -0.2794)
			(end 0.12065 -0.2794)
			(stroke
				(width 0.1)
				(type default)
			)
			(layer "F.Fab")
		)
		(fp_line
			(start 0.12065 -0.2794)
			(end 0.12065 -0.3048)
			(stroke
				(width 0.1)
				(type default)
			)
			(layer "F.Fab")
		)
		(fp_line
			(start 0.12065 -0.3048)
			(end 0.67945 -0.3048)
			(stroke
				(width 0.1)
				(type default)
			)
			(layer "F.Fab")
		)
		(fp_line
			(start 0.67945 -0.3048)
			(end 0.67945 0.3048)
			(stroke
				(width 0.1)
				(type default)
			)
			(layer "F.Fab")
		)
		(fp_line
			(start -0.67945 -0.305054)
			(end -0.12065 -0.305054)
			(stroke
				(width 0.1)
				(type default)
			)
			(layer "F.Fab")
		)
		(fp_line
			(start -0.12065 -0.305054)
			(end -0.12065 -0.2794)
			(stroke
				(width 0.1)
				(type default)
			)
			(layer "F.Fab")
		)
		(pad "1" smd circle
			(at -0.40005 0 270)
			(size 0 0)
			(layers "F.Cu" "F.Mask" "F.Paste")
			(net "CPU0_NMI_SYNC_FLOOD_N")
		)
		(pad "2" smd circle
			(at 0.40005 0 270)
			(size 0 0)
			(layers "F.Cu" "F.Mask" "F.Paste")
			(net "FM_CPU0_NMI_SYNC_FLOOD_N")
		)
	)
	(footprint ""
		(layer "F.Cu")
		(at 102.6668 -396.6972 90)
		(property "Reference" "R673"
			(at 0 0 90)
			(layer "F.SilkS")
			(hide yes)
			(effects
				(font
					(size 1.27 1.27)
				)
			)
		)
		(property "Value" ""
			(at 0 0 90)
			(layer "F.Fab")
			(effects
				(font
					(size 1.27 1.27)
				)
			)
		)
		(duplicate_pad_numbers_are_jumpers no)
		(fp_line
			(start 0.32512 -0.175006)
			(end 0.32512 0.175006)
			(stroke
				(width 0.1)
				(type default)
			)
			(layer "F.Fab")
		)
		(fp_line
			(start -0.32512 -0.175006)
			(end 0.32512 -0.175006)
			(stroke
				(width 0.1)
				(type default)
			)
			(layer "F.Fab")
		)
		(fp_line
			(start 0.32512 0.175006)
			(end -0.32512 0.175006)
			(stroke
				(width 0.1)
				(type default)
			)
			(layer "F.Fab")
		)
		(fp_line
			(start -0.32512 0.175006)
			(end -0.32512 -0.175006)
			(stroke
				(width 0.1)
				(type default)
			)
			(layer "F.Fab")
		)
		(pad "1" smd rect
			(at -0.2667 0 90)
			(size 0.3048 0.381)
			(layers "F.Cu" "F.Mask" "F.Paste")
			(net "SMB_RT_CPU1_P0_ROM_R_SDA")
		)
		(pad "2" smd rect
			(at 0.2667 0 270)
			(size 0.3048 0.381)
			(layers "F.Cu" "F.Mask" "F.Paste")
			(net "SMB_RT_CPU1_P0_ROM_SDA")
		)
	)
)
